(kicad_pcb
	(version 20260206)
	(generator "pcbnew")
	(generator_version "10.0")
	(general
		(thickness 1.6)
		(legacy_teardrops no)
	)
	(paper "A4")
	(title_block
		(title "04192023_DAF0TMB3IC0_F0TG_MB_C_brd_V02_OCP.brd")
		(comment 1 "Grand Teton / footprints 2851-2855 of 8354")
	)
	(layers
		(0 "F.Cu" signal "TOP")
		(4 "In1.Cu" signal "GND")
		(6 "In2.Cu" signal "IN1")
		(8 "In3.Cu" signal "GND1")
		(10 "In4.Cu" signal "IN2")
		(12 "In5.Cu" signal "GND2")
		(14 "In6.Cu" signal "IN3")
		(16 "In7.Cu" signal "GND3")
		(18 "In8.Cu" signal "VCC")
		(20 "In9.Cu" signal "VCC1")
		(22 "In10.Cu" signal "GND4")
		(24 "In11.Cu" signal "IN4")
		(26 "In12.Cu" signal "GND5")
		(28 "In13.Cu" signal "IN5")
		(30 "In14.Cu" signal "GND6")
		(32 "In15.Cu" signal "IN6")
		(34 "In16.Cu" signal "GND7")
		(2 "B.Cu" signal "BOTTOM")
		(9 "F.Adhes" user "F.Adhesive")
		(11 "B.Adhes" user "B.Adhesive")
		(13 "F.Paste" user "Package Geometry/Pastemask Top")
		(15 "B.Paste" user "Package Geometry/Pastemask Bottom")
		(5 "F.SilkS" user "Ref Des/Silkscreen Top")
		(7 "B.SilkS" user "Ref Des/Silkscreen Bottom")
		(1 "F.Mask" user "Board Geometry/Soldermask Top")
		(3 "B.Mask" user "Board Geometry/Soldermask Bottom")
		(17 "Dwgs.User" user "User.Drawings")
		(19 "Cmts.User" user "User.Comments")
		(21 "Eco1.User" user "User.Eco1")
		(23 "Eco2.User" user "User.Eco2")
		(25 "Edge.Cuts" user "Board Geometry/Outline")
		(27 "Margin" user)
		(31 "F.CrtYd" user "Package Geometry/Place Bound Top")
		(29 "B.CrtYd" user "Package Geometry/Place Bound Bottom")
		(35 "F.Fab" user "Ref Des/Assembly Top")
		(33 "B.Fab" user "Ref Des/Assembly Bottom")
	)
	(footprint ""
		(layer "F.Cu")
		(at 74.409046 -62.969394 -90)
		(property "Reference" "R1174"
			(at 0 0 270)
			(layer "F.SilkS")
			(hide yes)
			(effects
				(font
					(size 1.27 1.27)
				)
			)
		)
		(property "Value" ""
			(at 0 0 270)
			(layer "F.Fab")
			(effects
				(font
					(size 1.27 1.27)
				)
			)
		)
		(duplicate_pad_numbers_are_jumpers no)
		(fp_line
			(start -0.7874 0.4064)
			(end -0.7874 -0.4064)
			(stroke
				(width 0.1524)
				(type default)
			)
			(layer "F.SilkS")
		)
		(fp_line
			(start 0.7874 0.4064)
			(end -0.7874 0.4064)
			(stroke
				(width 0.1524)
				(type default)
			)
			(layer "F.SilkS")
		)
		(fp_line
			(start -0.7874 -0.4064)
			(end 0.7874 -0.4064)
			(stroke
				(width 0.1524)
				(type default)
			)
			(layer "F.SilkS")
		)
		(fp_line
			(start 0.7874 -0.4064)
			(end 0.7874 0.4064)
			(stroke
				(width 0.1524)
				(type default)
			)
			(layer "F.SilkS")
		)
		(fp_line
			(start -0.67945 0.3048)
			(end -0.67945 -0.305054)
			(stroke
				(width 0.1)
				(type default)
			)
			(layer "F.Fab")
		)
		(fp_line
			(start -0.12065 0.3048)
			(end -0.67945 0.3048)
			(stroke
				(width 0.1)
				(type default)
			)
			(layer "F.Fab")
		)
		(fp_line
			(start 0.120396 0.3048)
			(end 0.120396 0.2794)
			(stroke
				(width 0.1)
				(type default)
			)
			(layer "F.Fab")
		)
		(fp_line
			(start 0.67945 0.3048)
			(end 0.120396 0.3048)
			(stroke
				(width 0.1)
				(type default)
			)
			(layer "F.Fab")
		)
		(fp_line
			(start -0.12065 0.2794)
			(end -0.12065 0.3048)
			(stroke
				(width 0.1)
				(type default)
			)
			(layer "F.Fab")
		)
		(fp_line
			(start 0.120396 0.2794)
			(end -0.12065 0.2794)
			(stroke
				(width 0.1)
				(type default)
			)
			(layer "F.Fab")
		)
		(fp_line
			(start -0.12065 -0.2794)
			(end 0.12065 -0.2794)
			(stroke
				(width 0.1)
				(type default)
			)
			(layer "F.Fab")
		)
		(fp_line
			(start 0.12065 -0.2794)
			(end 0.12065 -0.3048)
			(stroke
				(width 0.1)
				(type default)
			)
			(layer "F.Fab")
		)
		(fp_line
			(start 0.12065 -0.3048)
			(end 0.67945 -0.3048)
			(stroke
				(width 0.1)
				(type default)
			)
			(layer "F.Fab")
		)
		(fp_line
			(start 0.67945 -0.3048)
			(end 0.67945 0.3048)
			(stroke
				(width 0.1)
				(type default)
			)
			(layer "F.Fab")
		)
		(fp_line
			(start -0.67945 -0.305054)
			(end -0.12065 -0.305054)
			(stroke
				(width 0.1)
				(type default)
			)
			(layer "F.Fab")
		)
		(fp_line
			(start -0.12065 -0.305054)
			(end -0.12065 -0.2794)
			(stroke
				(width 0.1)
				(type default)
			)
			(layer "F.Fab")
		)
		(pad "1" smd circle
			(at -0.40005 0 270)
			(size 0 0)
			(layers "F.Cu" "F.Mask" "F.Paste")
			(net "RST_PERST_OCP_V3_2_N")
		)
		(pad "2" smd circle
			(at 0.40005 0 270)
			(size 0 0)
			(layers "F.Cu" "F.Mask" "F.Paste")
			(net "RST_PERST_OCP_V3_2_R_N")
		)
	)
	(footprint ""
		(layer "F.Cu")
		(at 105.918 -423.291 90)
		(property "Reference" "C1963"
			(at 0 0 90)
			(layer "F.SilkS")
			(hide yes)
			(effects
				(font
					(size 1.27 1.27)
				)
			)
		)
		(property "Value" ""
			(at 0 0 90)
			(layer "F.Fab")
			(effects
				(font
					(size 1.27 1.27)
				)
			)
		)
		(duplicate_pad_numbers_are_jumpers no)
		(fp_line
			(start 0.7874 -0.4064)
			(end 0.7874 0.4064)
			(stroke
				(width 0.1524)
				(type default)
			)
			(layer "F.SilkS")
		)
		(fp_line
			(start -0.7874 -0.4064)
			(end 0.7874 -0.4064)
			(stroke
				(width 0.1524)
				(type default)
			)
			(layer "F.SilkS")
		)
		(fp_line
			(start 0.7874 0.4064)
			(end -0.7874 0.4064)
			(stroke
				(width 0.1524)
				(type default)
			)
			(layer "F.SilkS")
		)
		(fp_line
			(start -0.7874 0.4064)
			(end -0.7874 -0.4064)
			(stroke
				(width 0.1524)
				(type default)
			)
			(layer "F.SilkS")
		)
		(fp_line
			(start -0.12065 -0.305054)
			(end -0.12065 -0.2794)
			(stroke
				(width 0.1)
				(type default)
			)
			(layer "F.Fab")
		)
		(fp_line
			(start -0.67945 -0.305054)
			(end -0.12065 -0.305054)
			(stroke
				(width 0.1)
				(type default)
			)
			(layer "F.Fab")
		)
		(fp_line
			(start 0.67945 -0.3048)
			(end 0.67945 0.3048)
			(stroke
				(width 0.1)
				(type default)
			)
			(layer "F.Fab")
		)
		(fp_line
			(start 0.12065 -0.3048)
			(end 0.67945 -0.3048)
			(stroke
				(width 0.1)
				(type default)
			)
			(layer "F.Fab")
		)
		(fp_line
			(start 0.12065 -0.2794)
			(end 0.12065 -0.3048)
			(stroke
				(width 0.1)
				(type default)
			)
			(layer "F.Fab")
		)
		(fp_line
			(start -0.12065 -0.2794)
			(end 0.12065 -0.2794)
			(stroke
				(width 0.1)
				(type default)
			)
			(layer "F.Fab")
		)
		(fp_line
			(start 0.120396 0.2794)
			(end -0.12065 0.2794)
			(stroke
				(width 0.1)
				(type default)
			)
			(layer "F.Fab")
		)
		(fp_line
			(start -0.12065 0.2794)
			(end -0.12065 0.3048)
			(stroke
				(width 0.1)
				(type default)
			)
			(layer "F.Fab")
		)
		(fp_line
			(start 0.67945 0.3048)
			(end 0.120396 0.3048)
			(stroke
				(width 0.1)
				(type default)
			)
			(layer "F.Fab")
		)
		(fp_line
			(start 0.120396 0.3048)
			(end 0.120396 0.2794)
			(stroke
				(width 0.1)
				(type default)
			)
			(layer "F.Fab")
		)
		(fp_line
			(start -0.12065 0.3048)
			(end -0.67945 0.3048)
			(stroke
				(width 0.1)
				(type default)
			)
			(layer "F.Fab")
		)
		(fp_line
			(start -0.67945 0.3048)
			(end -0.67945 -0.305054)
			(stroke
				(width 0.1)
				(type default)
			)
			(layer "F.Fab")
		)
		(pad "1" smd circle
			(at -0.40005 0 90)
			(size 0 0)
			(layers "F.Cu" "F.Mask" "F.Paste")
			(net "P3V3_AUX")
		)
		(pad "2" smd circle
			(at 0.40005 0 90)
			(size 0 0)
			(layers "F.Cu" "F.Mask" "F.Paste")
			(net "GND")
		)
	)
	(footprint ""
		(layer "F.Cu")
		(at 62.043564 -16.220948 -90)
		(property "Reference" "R3170"
			(at 0 0 270)
			(layer "F.SilkS")
			(hide yes)
			(effects
				(font
					(size 1.27 1.27)
				)
			)
		)
		(property "Value" ""
			(at 0 0 270)
			(layer "F.Fab")
			(effects
				(font
					(size 1.27 1.27)
				)
			)
		)
		(duplicate_pad_numbers_are_jumpers no)
		(fp_line
			(start -0.7874 0.4064)
			(end -0.7874 -0.4064)
			(stroke
				(width 0.1524)
				(type default)
			)
			(layer "F.SilkS")
		)
		(fp_line
			(start 0.7874 0.4064)
			(end -0.7874 0.4064)
			(stroke
				(width 0.1524)
				(type default)
			)
			(layer "F.SilkS")
		)
		(fp_line
			(start -0.7874 -0.4064)
			(end 0.7874 -0.4064)
			(stroke
				(width 0.1524)
				(type default)
			)
			(layer "F.SilkS")
		)
		(fp_line
			(start 0.7874 -0.4064)
			(end 0.7874 0.4064)
			(stroke
				(width 0.1524)
				(type default)
			)
			(layer "F.SilkS")
		)
		(fp_line
			(start -0.67945 0.3048)
			(end -0.67945 -0.305054)
			(stroke
				(width 0.1)
				(type default)
			)
			(layer "F.Fab")
		)
		(fp_line
			(start -0.12065 0.3048)
			(end -0.67945 0.3048)
			(stroke
				(width 0.1)
				(type default)
			)
			(layer "F.Fab")
		)
		(fp_line
			(start 0.120396 0.3048)
			(end 0.120396 0.2794)
			(stroke
				(width 0.1)
				(type default)
			)
			(layer "F.Fab")
		)
		(fp_line
			(start 0.67945 0.3048)
			(end 0.120396 0.3048)
			(stroke
				(width 0.1)
				(type default)
			)
			(layer "F.Fab")
		)
		(fp_line
			(start -0.12065 0.2794)
			(end -0.12065 0.3048)
			(stroke
				(width 0.1)
				(type default)
			)
			(layer "F.Fab")
		)
		(fp_line
			(start 0.120396 0.2794)
			(end -0.12065 0.2794)
			(stroke
				(width 0.1)
				(type default)
			)
			(layer "F.Fab")
		)
		(fp_line
			(start -0.12065 -0.2794)
			(end 0.12065 -0.2794)
			(stroke
				(width 0.1)
				(type default)
			)
			(layer "F.Fab")
		)
		(fp_line
			(start 0.12065 -0.2794)
			(end 0.12065 -0.3048)
			(stroke
				(width 0.1)
				(type default)
			)
			(layer "F.Fab")
		)
		(fp_line
			(start 0.12065 -0.3048)
			(end 0.67945 -0.3048)
			(stroke
				(width 0.1)
				(type default)
			)
			(layer "F.Fab")
		)
		(fp_line
			(start 0.67945 -0.3048)
			(end 0.67945 0.3048)
			(stroke
				(width 0.1)
				(type default)
			)
			(layer "F.Fab")
		)
		(fp_line
			(start -0.67945 -0.305054)
			(end -0.12065 -0.305054)
			(stroke
				(width 0.1)
				(type default)
			)
			(layer "F.Fab")
		)
		(fp_line
			(start -0.12065 -0.305054)
			(end -0.12065 -0.2794)
			(stroke
				(width 0.1)
				(type default)
			)
			(layer "F.Fab")
		)
		(pad "1" smd circle
			(at -0.40005 0 270)
			(size 0 0)
			(layers "F.Cu" "F.Mask" "F.Paste")
			(net "OCP_V3_2_ISO_BIF1_EN")
		)
		(pad "2" smd circle
			(at 0.40005 0 270)
			(size 0 0)
			(layers "F.Cu" "F.Mask" "F.Paste")
			(net "OCP_V3_2_BIF1_R_N")
		)
	)
	(footprint ""
		(layer "F.Cu")
		(at 33.363662 -429.790098 90)
		(property "Reference" "R3270"
			(at 0 0 90)
			(layer "F.SilkS")
			(hide yes)
			(effects
				(font
					(size 1.27 1.27)
				)
			)
		)
		(property "Value" ""
			(at 0 0 90)
			(layer "F.Fab")
			(effects
				(font
					(size 1.27 1.27)
				)
			)
		)
		(duplicate_pad_numbers_are_jumpers no)
		(fp_line
			(start 0.7874 -0.4064)
			(end 0.7874 0.4064)
			(stroke
				(width 0.1524)
				(type default)
			)
			(layer "F.SilkS")
		)
		(fp_line
			(start -0.7874 -0.4064)
			(end 0.7874 -0.4064)
			(stroke
				(width 0.1524)
				(type default)
			)
			(layer "F.SilkS")
		)
		(fp_line
			(start 0.7874 0.4064)
			(end -0.7874 0.4064)
			(stroke
				(width 0.1524)
				(type default)
			)
			(layer "F.SilkS")
		)
		(fp_line
			(start -0.7874 0.4064)
			(end -0.7874 -0.4064)
			(stroke
				(width 0.1524)
				(type default)
			)
			(layer "F.SilkS")
		)
		(fp_line
			(start -0.12065 -0.305054)
			(end -0.12065 -0.2794)
			(stroke
				(width 0.1)
				(type default)
			)
			(layer "F.Fab")
		)
		(fp_line
			(start -0.67945 -0.305054)
			(end -0.12065 -0.305054)
			(stroke
				(width 0.1)
				(type default)
			)
			(layer "F.Fab")
		)
		(fp_line
			(start 0.67945 -0.3048)
			(end 0.67945 0.3048)
			(stroke
				(width 0.1)
				(type default)
			)
			(layer "F.Fab")
		)
		(fp_line
			(start 0.12065 -0.3048)
			(end 0.67945 -0.3048)
			(stroke
				(width 0.1)
				(type default)
			)
			(layer "F.Fab")
		)
		(fp_line
			(start 0.12065 -0.2794)
			(end 0.12065 -0.3048)
			(stroke
				(width 0.1)
				(type default)
			)
			(layer "F.Fab")
		)
		(fp_line
			(start -0.12065 -0.2794)
			(end 0.12065 -0.2794)
			(stroke
				(width 0.1)
				(type default)
			)
			(layer "F.Fab")
		)
		(fp_line
			(start 0.120396 0.2794)
			(end -0.12065 0.2794)
			(stroke
				(width 0.1)
				(type default)
			)
			(layer "F.Fab")
		)
		(fp_line
			(start -0.12065 0.2794)
			(end -0.12065 0.3048)
			(stroke
				(width 0.1)
				(type default)
			)
			(layer "F.Fab")
		)
		(fp_line
			(start 0.67945 0.3048)
			(end 0.120396 0.3048)
			(stroke
				(width 0.1)
				(type default)
			)
			(layer "F.Fab")
		)
		(fp_line
			(start 0.120396 0.3048)
			(end 0.120396 0.2794)
			(stroke
				(width 0.1)
				(type default)
			)
			(layer "F.Fab")
		)
		(fp_line
			(start -0.12065 0.3048)
			(end -0.67945 0.3048)
			(stroke
				(width 0.1)
				(type default)
			)
			(layer "F.Fab")
		)
		(fp_line
			(start -0.67945 0.3048)
			(end -0.67945 -0.305054)
			(stroke
				(width 0.1)
				(type default)
			)
			(layer "F.Fab")
		)
		(pad "1" smd circle
			(at -0.40005 0 90)
			(size 0 0)
			(layers "F.Cu" "F.Mask" "F.Paste")
			(net "FM_P2E_FGB")
		)
		(pad "2" smd circle
			(at 0.40005 0 90)
			(size 0 0)
			(layers "F.Cu" "F.Mask" "F.Paste")
			(net "GND")
		)
	)
	(footprint ""
		(layer "F.Cu")
		(at 159.639 -106.426 180)
		(property "Reference" "Q9003"
			(at 2.59461 -2.129028 0)
			(unlocked yes)
			(layer "F.SilkS")
			(effects
				(font
					(size 0.7874 0.5842)
					(thickness 0.1524)
				)
				(justify left)
			)
		)
		(property "Value" ""
			(at 0 0 180)
			(layer "F.Fab")
			(effects
				(font
					(size 1.27 1.27)
				)
			)
		)
		(duplicate_pad_numbers_are_jumpers no)
		(fp_line
			(start 1.332738 1.100074)
			(end -1.332738 1.100074)
			(stroke
				(width 0.1524)
				(type default)
			)
			(layer "F.SilkS")
		)
		(fp_line
			(start 1.332738 -1.100074)
			(end 1.332738 1.100074)
			(stroke
				(width 0.1524)
				(type default)
			)
			(layer "F.SilkS")
		)
		(fp_line
			(start 0.4826 -1.100074)
			(end 1.332738 -1.100074)
			(stroke
				(width 0.1524)
				(type default)
			)
			(layer "F.SilkS")
		)
		(fp_line
			(start 0 -0.541274)
			(end 0.4826 -1.100074)
			(stroke
				(width 0.1524)
				(type default)
			)
			(layer "F.SilkS")
		)
		(fp_line
			(start -0.4826 -1.100074)
			(end 0 -0.541274)
			(stroke
				(width 0.1524)
				(type default)
			)
			(layer "F.SilkS")
		)
		(fp_line
			(start -1.332738 1.100074)
			(end -1.332738 -1.100074)
			(stroke
				(width 0.1524)
				(type default)
			)
			(layer "F.SilkS")
		)
		(fp_line
			(start -1.332738 -1.100074)
			(end -0.4826 -1.100074)
			(stroke
				(width 0.1524)
				(type default)
			)
			(layer "F.SilkS")
		)
		(fp_poly
			(pts
				(xy -2.28219 -1.735074) (xy -1.785874 -2.23139) (xy -1.537716 -1.486916)
			)
			(stroke
				(width 0)
				(type default)
			)
			(fill yes)
			(layer "F.SilkS")
		)
		(fp_line
			(start 0.674878 1.100074)
			(end -0.674878 1.100074)
			(stroke
				(width 0.1)
				(type default)
			)
			(layer "F.Fab")
		)
		(fp_line
			(start 0.674878 -1.100074)
			(end 0.674878 1.100074)
			(stroke
				(width 0.1)
				(type default)
			)
			(layer "F.Fab")
		)
		(fp_line
			(start -0.674878 1.100074)
			(end -0.674878 -1.100074)
			(stroke
				(width 0.1)
				(type default)
			)
			(layer "F.Fab")
		)
		(fp_line
			(start -0.674878 -1.100074)
			(end 0.674878 -1.100074)
			(stroke
				(width 0.1)
				(type default)
			)
			(layer "F.Fab")
		)
		(fp_poly
			(pts
				(xy -2.2352 -0.298958) (xy -2.2352 -1.001014) (xy -1.533144 -0.649986)
			)
			(stroke
				(width 0)
				(type default)
			)
			(fill yes)
			(layer "F.Fab")
		)
		(pad "1" smd rect
			(at -0.94996 -0.649986 270)
			(size 0.4318 0.508)
			(layers "F.Cu" "F.Mask" "F.Paste")
			(net "GND")
		)
		(pad "2" smd rect
			(at -0.94996 0 270)
			(size 0.4318 0.508)
			(layers "F.Cu" "F.Mask" "F.Paste")
			(net "IRQ_HSC_FAULT_N")
		)
		(pad "3" smd rect
			(at -0.94996 0.649986 270)
			(size 0.4318 0.508)
			(layers "F.Cu" "F.Mask" "F.Paste")
			(net "IRQ_HSC_FAULT_BUF_N")
		)
		(pad "4" smd rect
			(at 0.94996 0.649986 270)
			(size 0.4318 0.508)
			(layers "F.Cu" "F.Mask" "F.Paste")
			(net "GND")
		)
		(pad "5" smd rect
			(at 0.94996 0 270)
			(size 0.4318 0.508)
			(layers "F.Cu" "F.Mask" "F.Paste")
			(net "IRQ_HSC_FAULT")
		)
		(pad "6" smd rect
			(at 0.94996 -0.649986 270)
			(size 0.4318 0.508)
			(layers "F.Cu" "F.Mask" "F.Paste")
			(net "IRQ_HSC_FAULT")
		)
	)
)
